# BASEBOARD_FAB2 (Tioga Pass) — schematic netlist excerpt (pin names and nets, part order shuffled) for the footprints in the layout excerpt that follows; sources: Cadence DE-HDL packaged netlist, KiCad conversion of Wiwynn_Tioga_Pass_MB.brd

R12W32  RES  0.0 5% EMPTY  pkg 0402  page 223 : A = TP_PVDDQ_GHJ_MP1 ; B = PWRGD_PVDDQ_GHJ
R7W12  RES  0.0 5% CHIP  pkg 0402  page 120 : A = FM_CPU1_RC_ERROR_N ; B = FM_CPU1_RC_ERROR_R1_N
R8B5  RES  4.75K 1% CHIP  pkg 0402  page 91 : A = PVPP_ABC ; B = LED_HFI0_CPU0_N

(kicad_pcb
	(version 20260206)
	(generator "pcbnew")
	(generator_version "10.0")
	(general
		(thickness 1.6)
		(legacy_teardrops no)
	)
	(paper "A4")
	(title_block
		(title "Wiwynn_Tioga_Pass_MB.brd")
		(comment 1 "Tioga Pass / footprints 474-476 of 4770")
	)
	(layers
		(0 "F.Cu" signal "TOP")
		(4 "In1.Cu" signal "L2GND")
		(6 "In2.Cu" signal "L3")
		(8 "In3.Cu" signal "L4GND")
		(10 "In4.Cu" signal "L5")
		(12 "In5.Cu" signal "L6GND")
		(14 "In6.Cu" signal "L7VCC")
		(16 "In7.Cu" signal "L8VCC")
		(18 "In8.Cu" signal "L9GND")
		(20 "In9.Cu" signal "L10")
		(22 "In10.Cu" signal "L11GND")
		(24 "In11.Cu" signal "L12")
		(26 "In12.Cu" signal "L13GND")
		(2 "B.Cu" signal "BOTTOM")
		(9 "F.Adhes" user "F.Adhesive")
		(11 "B.Adhes" user "B.Adhesive")
		(13 "F.Paste" user "Package Geometry/Pastemask Top")
		(15 "B.Paste" user "Package Geometry/Pastemask Bottom")
		(5 "F.SilkS" user "Ref Des/Silkscreen Top")
		(7 "B.SilkS" user "Ref Des/Silkscreen Bottom")
		(1 "F.Mask" user "Board Geometry/Soldermask Top")
		(3 "B.Mask" user "Board Geometry/Soldermask Bottom")
		(17 "Dwgs.User" user "User.Drawings")
		(19 "Cmts.User" user "User.Comments")
		(21 "Eco1.User" user "User.Eco1")
		(23 "Eco2.User" user "User.Eco2")
		(25 "Edge.Cuts" user "Board Geometry/Outline")
		(27 "Margin" user)
		(31 "F.CrtYd" user "Package Geometry/Place Bound Top")
		(29 "B.CrtYd" user "Package Geometry/Place Bound Bottom")
		(35 "F.Fab" user "Ref Des/Assembly Top")
		(33 "B.Fab" user "Ref Des/Assembly Bottom")
	)
	(footprint ""
		(layer "F.Cu")
		(at 411.6578 -102.4636 180)
		(property "Reference" "R7W12"
			(at -0.8382 -0.67818 180)
			(unlocked yes)
			(layer "F.SilkS")
			(effects
				(font
					(size 0.4064 0.254)
					(thickness 0.1524)
				)
				(justify left)
			)
		)
		(property "Value" ""
			(at 0 0 180)
			(layer "F.Fab")
			(effects
				(font
					(size 1.27 1.27)
				)
			)
		)
		(duplicate_pad_numbers_are_jumpers no)
		(fp_poly
			(pts
				(xy -0.2794 -0.1016) (xy 0.2794 -0.1016) (xy 0.2794 0.9906) (xy -0.2794 0.9906)
			)
			(stroke
				(width 0)
				(type default)
			)
			(fill no)
			(layer "F.CrtYd")
		)
		(fp_line
			(start 0.2794 0.9906)
			(end 0.2794 -0.1016)
			(stroke
				(width 0.1)
				(type default)
			)
			(layer "F.Fab")
		)
		(fp_line
			(start 0.2794 -0.1016)
			(end -0.2794 -0.1016)
			(stroke
				(width 0.1)
				(type default)
			)
			(layer "F.Fab")
		)
		(fp_line
			(start -0.2794 0.9906)
			(end 0.2794 0.9906)
			(stroke
				(width 0.1)
				(type default)
			)
			(layer "F.Fab")
		)
		(fp_line
			(start -0.2794 -0.1016)
			(end -0.2794 0.9906)
			(stroke
				(width 0.1)
				(type default)
			)
			(layer "F.Fab")
		)
		(pad "1" smd rect
			(at 0 0 180)
			(size 0.508 0.508)
			(layers "F.Cu" "F.Mask" "F.Paste")
			(net "FM_CPU1_RC_ERROR_N")
		)
		(pad "2" smd rect
			(at 0 0.889 180)
			(size 0.508 0.508)
			(layers "F.Cu" "F.Mask" "F.Paste")
			(net "FM_CPU1_RC_ERROR_R1_N")
		)
		(zone
			(layer "F.Cu")
			(hatch none 0.5)
			(connect_pads
				(clearance 0)
			)
			(min_thickness 0.25)
			(keepout
				(tracks not_allowed)
				(vias allowed)
				(pads allowed)
				(copperpour not_allowed)
				(footprints allowed)
			)
			(placement
				(enabled no)
				(sheetname "")
			)
			(fill
				(thermal_gap 0.5)
				(thermal_bridge_width 0.5)
				(island_removal_mode 0)
			)
			(polygon
				(pts
					(xy 411.9118 -103.0986) (xy 411.4038 -103.0986) (xy 411.4038 -102.7176) (xy 411.9118 -102.7176)
				)
			)
		)
		(zone
			(layer "F.Cu")
			(hatch none 0.5)
			(connect_pads
				(clearance 0)
			)
			(min_thickness 0.25)
			(keepout
				(tracks allowed)
				(vias not_allowed)
				(pads allowed)
				(copperpour not_allowed)
				(footprints allowed)
			)
			(placement
				(enabled no)
				(sheetname "")
			)
			(fill
				(thermal_gap 0.5)
				(thermal_bridge_width 0.5)
				(island_removal_mode 0)
			)
			(polygon
				(pts
					(xy 411.9118 -102.7176) (xy 411.4038 -102.7176) (xy 411.4038 -103.0986) (xy 411.9118 -103.0986)
				)
			)
		)
	)
	(footprint ""
		(layer "F.Cu")
		(at 11.89863 -3.541268 180)
		(property "Reference" "R12W32"
			(at -0.8382 -0.67818 180)
			(unlocked yes)
			(layer "F.SilkS")
			(effects
				(font
					(size 0.4064 0.254)
					(thickness 0.1524)
				)
				(justify left)
			)
		)
		(property "Value" ""
			(at 0 0 180)
			(layer "F.Fab")
			(effects
				(font
					(size 1.27 1.27)
				)
			)
		)
		(duplicate_pad_numbers_are_jumpers no)
		(fp_poly
			(pts
				(xy -0.2794 -0.1016) (xy 0.2794 -0.1016) (xy 0.2794 0.9906) (xy -0.2794 0.9906)
			)
			(stroke
				(width 0)
				(type default)
			)
			(fill no)
			(layer "F.CrtYd")
		)
		(fp_line
			(start 0.2794 0.9906)
			(end 0.2794 -0.1016)
			(stroke
				(width 0.1)
				(type default)
			)
			(layer "F.Fab")
		)
		(fp_line
			(start 0.2794 -0.1016)
			(end -0.2794 -0.1016)
			(stroke
				(width 0.1)
				(type default)
			)
			(layer "F.Fab")
		)
		(fp_line
			(start -0.2794 0.9906)
			(end 0.2794 0.9906)
			(stroke
				(width 0.1)
				(type default)
			)
			(layer "F.Fab")
		)
		(fp_line
			(start -0.2794 -0.1016)
			(end -0.2794 0.9906)
			(stroke
				(width 0.1)
				(type default)
			)
			(layer "F.Fab")
		)
		(pad "1" smd rect
			(at 0 0 180)
			(size 0.508 0.508)
			(layers "F.Cu" "F.Mask" "F.Paste")
			(net "TP_PVDDQ_GHJ_MP1")
		)
		(pad "2" smd rect
			(at 0 0.889 180)
			(size 0.508 0.508)
			(layers "F.Cu" "F.Mask" "F.Paste")
			(net "PWRGD_PVDDQ_GHJ")
		)
		(zone
			(layer "F.Cu")
			(hatch none 0.5)
			(connect_pads
				(clearance 0)
			)
			(min_thickness 0.25)
			(keepout
				(tracks not_allowed)
				(vias allowed)
				(pads allowed)
				(copperpour not_allowed)
				(footprints allowed)
			)
			(placement
				(enabled no)
				(sheetname "")
			)
			(fill
				(thermal_gap 0.5)
				(thermal_bridge_width 0.5)
				(island_removal_mode 0)
			)
			(polygon
				(pts
					(xy 12.15263 -4.176268) (xy 11.64463 -4.176268) (xy 11.64463 -3.795268) (xy 12.15263 -3.795268)
				)
			)
		)
		(zone
			(layer "F.Cu")
			(hatch none 0.5)
			(connect_pads
				(clearance 0)
			)
			(min_thickness 0.25)
			(keepout
				(tracks allowed)
				(vias not_allowed)
				(pads allowed)
				(copperpour not_allowed)
				(footprints allowed)
			)
			(placement
				(enabled no)
				(sheetname "")
			)
			(fill
				(thermal_gap 0.5)
				(thermal_bridge_width 0.5)
				(island_removal_mode 0)
			)
			(polygon
				(pts
					(xy 12.15263 -3.795268) (xy 11.64463 -3.795268) (xy 11.64463 -4.176268) (xy 12.15263 -4.176268)
				)
			)
		)
	)
	(footprint ""
		(layer "F.Cu")
		(at 411.444694 -131.805172 90)
		(property "Reference" "R8B5"
			(at 0 0 90)
			(layer "F.SilkS")
			(hide yes)
			(effects
				(font
					(size 1.27 1.27)
				)
			)
		)
		(property "Value" ""
			(at 0 0 90)
			(layer "F.Fab")
			(effects
				(font
					(size 1.27 1.27)
				)
			)
		)
		(duplicate_pad_numbers_are_jumpers no)
		(fp_poly
			(pts
				(xy -0.2794 -0.1016) (xy 0.2794 -0.1016) (xy 0.2794 0.9906) (xy -0.2794 0.9906)
			)
			(stroke
				(width 0)
				(type default)
			)
			(fill no)
			(layer "F.CrtYd")
		)
		(fp_line
			(start 0.2794 -0.1016)
			(end -0.2794 -0.1016)
			(stroke
				(width 0.1)
				(type default)
			)
			(layer "F.Fab")
		)
		(fp_line
			(start -0.2794 -0.1016)
			(end -0.2794 0.9906)
			(stroke
				(width 0.1)
				(type default)
			)
			(layer "F.Fab")
		)
		(fp_line
			(start 0.2794 0.9906)
			(end 0.2794 -0.1016)
			(stroke
				(width 0.1)
				(type default)
			)
			(layer "F.Fab")
		)
		(fp_line
			(start -0.2794 0.9906)
			(end 0.2794 0.9906)
			(stroke
				(width 0.1)
				(type default)
			)
			(layer "F.Fab")
		)
		(pad "1" smd rect
			(at 0 0 90)
			(size 0.508 0.508)
			(layers "F.Cu" "F.Mask" "F.Paste")
			(net "PVPP_ABC")
		)
		(pad "2" smd rect
			(at 0 0.889 90)
			(size 0.508 0.508)
			(layers "F.Cu" "F.Mask" "F.Paste")
			(net "LED_HFI0_CPU0_N")
		)
		(zone
			(layer "F.Cu")
			(hatch none 0.5)
			(connect_pads
				(clearance 0)
			)
			(min_thickness 0.25)
			(keepout
				(tracks allowed)
				(vias not_allowed)
				(pads allowed)
				(copperpour not_allowed)
				(footprints allowed)
			)
			(placement
				(enabled no)
				(sheetname "")
			)
			(fill
				(thermal_gap 0.5)
				(thermal_bridge_width 0.5)
				(island_removal_mode 0)
			)
			(polygon
				(pts
					(xy 411.698694 -131.551172) (xy 411.698694 -132.059172) (xy 412.079694 -132.059172) (xy 412.079694 -131.551172)
				)
			)
		)
		(zone
			(layer "F.Cu")
			(hatch none 0.5)
			(connect_pads
				(clearance 0)
			)
			(min_thickness 0.25)
			(keepout
				(tracks not_allowed)
				(vias allowed)
				(pads allowed)
				(copperpour not_allowed)
				(footprints allowed)
			)
			(placement
				(enabled no)
				(sheetname "")
			)
			(fill
				(thermal_gap 0.5)
				(thermal_bridge_width 0.5)
				(island_removal_mode 0)
			)
			(polygon
				(pts
					(xy 412.079694 -131.551172) (xy 412.079694 -132.059172) (xy 411.698694 -132.059172) (xy 411.698694 -131.551172)
				)
			)
		)
	)
)
